# T6G (Grand Teton) — schematic netlist excerpt (pin names and nets, part order shuffled) for the footprints in the layout excerpt that follows; sources: Cadence DE-HDL packaged netlist, KiCad conversion of 04192023_DAF0TMB3IC0_F0TG_MB_C_brd_V02_OCP.brd

D8003  SCHOTTKY_12  B0530WS7F EMPTY  pkg SOD323XB  page 86 : A = PWRGD_CHAF_CPU0_R1 ; C = P3V3_AUX
PC285_4  Q_CAP  0.1UF 25V 10% X7R  pkg 0402  page 212 : A = PVDDCR_CPU0_P1_VCCS ; B = GND

(kicad_pcb
	(version 20260206)
	(generator "pcbnew")
	(generator_version "10.0")
	(general
		(thickness 1.6)
		(legacy_teardrops no)
	)
	(paper "A4")
	(title_block
		(title "04192023_DAF0TMB3IC0_F0TG_MB_C_brd_V02_OCP.brd")
		(comment 1 "Grand Teton / footprints 3262-3263 of 8354")
	)
	(layers
		(0 "F.Cu" signal "TOP")
		(4 "In1.Cu" signal "GND")
		(6 "In2.Cu" signal "IN1")
		(8 "In3.Cu" signal "GND1")
		(10 "In4.Cu" signal "IN2")
		(12 "In5.Cu" signal "GND2")
		(14 "In6.Cu" signal "IN3")
		(16 "In7.Cu" signal "GND3")
		(18 "In8.Cu" signal "VCC")
		(20 "In9.Cu" signal "VCC1")
		(22 "In10.Cu" signal "GND4")
		(24 "In11.Cu" signal "IN4")
		(26 "In12.Cu" signal "GND5")
		(28 "In13.Cu" signal "IN5")
		(30 "In14.Cu" signal "GND6")
		(32 "In15.Cu" signal "IN6")
		(34 "In16.Cu" signal "GND7")
		(2 "B.Cu" signal "BOTTOM")
		(9 "F.Adhes" user "F.Adhesive")
		(11 "B.Adhes" user "B.Adhesive")
		(13 "F.Paste" user "Package Geometry/Pastemask Top")
		(15 "B.Paste" user "Package Geometry/Pastemask Bottom")
		(5 "F.SilkS" user "Ref Des/Silkscreen Top")
		(7 "B.SilkS" user "Ref Des/Silkscreen Bottom")
		(1 "F.Mask" user "Board Geometry/Soldermask Top")
		(3 "B.Mask" user "Board Geometry/Soldermask Bottom")
		(17 "Dwgs.User" user "User.Drawings")
		(19 "Cmts.User" user "User.Comments")
		(21 "Eco1.User" user "User.Eco1")
		(23 "Eco2.User" user "User.Eco2")
		(25 "Edge.Cuts" user "Board Geometry/Outline")
		(27 "Margin" user)
		(31 "F.CrtYd" user "Package Geometry/Place Bound Top")
		(29 "B.CrtYd" user "Package Geometry/Place Bound Bottom")
		(35 "F.Fab" user "Ref Des/Assembly Top")
		(33 "B.Fab" user "Ref Des/Assembly Bottom")
	)
	(footprint ""
		(layer "F.Cu")
		(at 204.597 -104.013)
		(property "Reference" "D8003"
			(at -1.405636 -1.31953 0)
			(unlocked yes)
			(layer "F.SilkS")
			(effects
				(font
					(size 0.7874 0.5842)
					(thickness 0.1524)
				)
				(justify left)
			)
		)
		(property "Value" ""
			(at 0 0 0)
			(layer "F.Fab")
			(effects
				(font
					(size 1.27 1.27)
				)
			)
		)
		(duplicate_pad_numbers_are_jumpers no)
		(fp_line
			(start -2.050796 -0.700024)
			(end 2.050796 -0.700024)
			(stroke
				(width 0.1524)
				(type default)
			)
			(layer "F.SilkS")
		)
		(fp_line
			(start -2.050796 0.700024)
			(end -2.050796 -0.700024)
			(stroke
				(width 0.1524)
				(type default)
			)
			(layer "F.SilkS")
		)
		(fp_line
			(start -0.30607 -0.500126)
			(end -0.30607 0.500126)
			(stroke
				(width 0.1524)
				(type default)
			)
			(layer "F.SilkS")
		)
		(fp_line
			(start -0.30607 0.500126)
			(end 0.193802 0)
			(stroke
				(width 0.1524)
				(type default)
			)
			(layer "F.SilkS")
		)
		(fp_line
			(start 0.193802 0)
			(end -0.30607 -0.500126)
			(stroke
				(width 0.1524)
				(type default)
			)
			(layer "F.SilkS")
		)
		(fp_line
			(start 0.293878 -0.500126)
			(end 0.293878 0.500126)
			(stroke
				(width 0.1524)
				(type default)
			)
			(layer "F.SilkS")
		)
		(fp_line
			(start 2.050796 -0.700024)
			(end 2.050796 0.700024)
			(stroke
				(width 0.1524)
				(type default)
			)
			(layer "F.SilkS")
		)
		(fp_line
			(start 2.050796 0.700024)
			(end -2.050796 0.700024)
			(stroke
				(width 0.1524)
				(type default)
			)
			(layer "F.SilkS")
		)
		(fp_line
			(start 2.051304 0.635)
			(end 2.152904 0.635)
			(stroke
				(width 0.1524)
				(type default)
			)
			(layer "F.SilkS")
		)
		(fp_line
			(start 2.051304 0.6985)
			(end 2.051304 0.635)
			(stroke
				(width 0.1524)
				(type default)
			)
			(layer "F.SilkS")
		)
		(fp_line
			(start 2.064004 -0.6985)
			(end 2.229104 -0.6985)
			(stroke
				(width 0.1524)
				(type default)
			)
			(layer "F.SilkS")
		)
		(fp_line
			(start 2.064004 -0.6731)
			(end 2.064004 -0.6985)
			(stroke
				(width 0.1524)
				(type default)
			)
			(layer "F.SilkS")
		)
		(fp_line
			(start 2.152904 -0.6985)
			(end 2.343404 -0.6985)
			(stroke
				(width 0.1524)
				(type default)
			)
			(layer "F.SilkS")
		)
		(fp_line
			(start 2.152904 0.635)
			(end 2.152904 -0.6985)
			(stroke
				(width 0.1524)
				(type default)
			)
			(layer "F.SilkS")
		)
		(fp_line
			(start 2.229104 -0.6985)
			(end 2.229104 0.6985)
			(stroke
				(width 0.1524)
				(type default)
			)
			(layer "F.SilkS")
		)
		(fp_line
			(start 2.229104 0.6985)
			(end 2.051304 0.6985)
			(stroke
				(width 0.1524)
				(type default)
			)
			(layer "F.SilkS")
		)
		(fp_line
			(start 2.343404 -0.6985)
			(end 2.343404 0.6985)
			(stroke
				(width 0.1524)
				(type default)
			)
			(layer "F.SilkS")
		)
		(fp_line
			(start 2.343404 0.6985)
			(end 2.216404 0.6985)
			(stroke
				(width 0.1524)
				(type default)
			)
			(layer "F.SilkS")
		)
		(fp_line
			(start -0.899922 -0.700024)
			(end 0.899922 -0.700024)
			(stroke
				(width 0.1)
				(type default)
			)
			(layer "F.Fab")
		)
		(fp_line
			(start -0.899922 0.700024)
			(end -0.899922 -0.700024)
			(stroke
				(width 0.1)
				(type default)
			)
			(layer "F.Fab")
		)
		(fp_line
			(start 0.899922 -0.700024)
			(end 0.899922 0.700024)
			(stroke
				(width 0.1)
				(type default)
			)
			(layer "F.Fab")
		)
		(fp_line
			(start 0.899922 0.700024)
			(end -0.899922 0.700024)
			(stroke
				(width 0.1)
				(type default)
			)
			(layer "F.Fab")
		)
		(fp_text user "+"
			(at -2.478532 -0.494792 90)
			(unlocked yes)
			(layer "F.SilkS")
			(effects
				(font
					(size 1.905 1.4224)
					(thickness 0.1524)
				)
				(justify left)
			)
		)
		(fp_text user "-"
			(at 3.947414 1.054862 180)
			(unlocked yes)
			(layer "F.SilkS")
			(effects
				(font
					(size 1.905 1.4224)
					(thickness 0.1524)
				)
				(justify left)
			)
		)
		(fp_text user "+"
			(at -3.123946 0.762 90)
			(unlocked yes)
			(layer "F.Fab")
			(effects
				(font
					(size 1.905 1.4224)
					(thickness 0.1524)
				)
				(justify left)
			)
		)
		(fp_text user "-"
			(at 3.880104 0.23495 180)
			(unlocked yes)
			(layer "F.Fab")
			(effects
				(font
					(size 1.905 1.4224)
					(thickness 0.1524)
				)
				(justify left)
			)
		)
		(pad "1" smd rect
			(at -1.199896 0 270)
			(size 0.6604 1.3716)
			(layers "F.Cu" "F.Mask" "F.Paste")
			(net "PWRGD_CHAF_CPU0_R1")
		)
		(pad "2" smd rect
			(at 1.199896 0 90)
			(size 0.6604 1.3716)
			(layers "F.Cu" "F.Mask" "F.Paste")
			(net "P3V3_AUX")
		)
	)
	(footprint ""
		(layer "F.Cu")
		(at 110.149894 -173.31436 -90)
		(property "Reference" "PC285_4"
			(at 0 0 270)
			(layer "F.SilkS")
			(hide yes)
			(effects
				(font
					(size 1.27 1.27)
				)
			)
		)
		(property "Value" ""
			(at 0 0 270)
			(layer "F.Fab")
			(effects
				(font
					(size 1.27 1.27)
				)
			)
		)
		(duplicate_pad_numbers_are_jumpers no)
		(fp_line
			(start -0.7874 0.4064)
			(end -0.7874 -0.4064)
			(stroke
				(width 0.1524)
				(type default)
			)
			(layer "F.SilkS")
		)
		(fp_line
			(start 0.7874 0.4064)
			(end -0.7874 0.4064)
			(stroke
				(width 0.1524)
				(type default)
			)
			(layer "F.SilkS")
		)
		(fp_line
			(start -0.7874 -0.4064)
			(end 0.7874 -0.4064)
			(stroke
				(width 0.1524)
				(type default)
			)
			(layer "F.SilkS")
		)
		(fp_line
			(start 0.7874 -0.4064)
			(end 0.7874 0.4064)
			(stroke
				(width 0.1524)
				(type default)
			)
			(layer "F.SilkS")
		)
		(fp_line
			(start -0.67945 0.3048)
			(end -0.67945 -0.305054)
			(stroke
				(width 0.1)
				(type default)
			)
			(layer "F.Fab")
		)
		(fp_line
			(start -0.12065 0.3048)
			(end -0.67945 0.3048)
			(stroke
				(width 0.1)
				(type default)
			)
			(layer "F.Fab")
		)
		(fp_line
			(start 0.120396 0.3048)
			(end 0.120396 0.2794)
			(stroke
				(width 0.1)
				(type default)
			)
			(layer "F.Fab")
		)
		(fp_line
			(start 0.67945 0.3048)
			(end 0.120396 0.3048)
			(stroke
				(width 0.1)
				(type default)
			)
			(layer "F.Fab")
		)
		(fp_line
			(start -0.12065 0.2794)
			(end -0.12065 0.3048)
			(stroke
				(width 0.1)
				(type default)
			)
			(layer "F.Fab")
		)
		(fp_line
			(start 0.120396 0.2794)
			(end -0.12065 0.2794)
			(stroke
				(width 0.1)
				(type default)
			)
			(layer "F.Fab")
		)
		(fp_line
			(start -0.12065 -0.2794)
			(end 0.12065 -0.2794)
			(stroke
				(width 0.1)
				(type default)
			)
			(layer "F.Fab")
		)
		(fp_line
			(start 0.12065 -0.2794)
			(end 0.12065 -0.3048)
			(stroke
				(width 0.1)
				(type default)
			)
			(layer "F.Fab")
		)
		(fp_line
			(start 0.12065 -0.3048)
			(end 0.67945 -0.3048)
			(stroke
				(width 0.1)
				(type default)
			)
			(layer "F.Fab")
		)
		(fp_line
			(start 0.67945 -0.3048)
			(end 0.67945 0.3048)
			(stroke
				(width 0.1)
				(type default)
			)
			(layer "F.Fab")
		)
		(fp_line
			(start -0.67945 -0.305054)
			(end -0.12065 -0.305054)
			(stroke
				(width 0.1)
				(type default)
			)
			(layer "F.Fab")
		)
		(fp_line
			(start -0.12065 -0.305054)
			(end -0.12065 -0.2794)
			(stroke
				(width 0.1)
				(type default)
			)
			(layer "F.Fab")
		)
		(pad "1" smd circle
			(at -0.40005 0 270)
			(size 0 0)
			(layers "F.Cu" "F.Mask" "F.Paste")
			(net "PVDDCR_CPU0_P1_VCCS")
		)
		(pad "2" smd circle
			(at 0.40005 0 270)
			(size 0 0)
			(layers "F.Cu" "F.Mask" "F.Paste")
			(net "GND")
		)
	)
)
